# BASEBOARD_FAB2 (Tioga Pass) — schematic netlist excerpt (pin names and nets, part order shuffled) for the footprints in the layout excerpt that follows; sources: Cadence DE-HDL packaged netlist, KiCad conversion of Wiwynn_Tioga_Pass_MB.brd

EU1C2  PXE1610B  IC  pkg QFN  page 206
  BPWM1  = VR_PVSA_CPU1_PWM
  APWM6  = NC
  APWM5  = VR_PVCCIN_CPU1_PWM5
  APWM4  = VR_PVCCIN_CPU1_PWM4
  APWM3  = VR_PVCCIN_CPU1_PWM3
  APWM2  = VR_PVCCIN_CPU1_PWM2
  APWM1  = VR_PVCCIN_CPU1_PWM1
  SDA  = SMB_VR_STBY_LVC3_SDA
  SCL  = SMB_VR_STBY_LVC3_SCL
  RESET_N  = NC
  AVRRDY  = VR_VRRDY_PVCCIN_CPU1
  AVREN  = VR_PVCCIN_CPU1_VREN
  VRHOT_N  = IRQ_PVCCIN_CPU1_VRHOT_LVC3_R_N
  PINALRT_N  = FM_PVCCIN_CPU1_PWR_IN_ALERT_N
  MP0  = PWRGD_PVSA_CPU1_R
  MP1  = NC
  VCLK  = SVID_VCLK_PVCCIN_CPU1
  VDIO  = SVID_VDIO_PVCCIN_CPU1
  VALRT_N  = SVID_VALERT_VCCIN_CPU1
  MP2  = PU_VR_PVCCIN_CPU1_FLT1_SMBALT_N
  AVSEN  = VSENSE_PVCCIN_CPU1_AVSP
  AVREF  = VSENSE_PVCCIN_CPU1_N
  AIREF1  = VR_PVCCIN_CPU1_AIREF1
  AISEN1  = ISENSE_PVCCIN_CPU1_PH1_IMON
  AIREF2  = VR_PVCCIN_CPU1_AIREF2
  AISEN2  = ISENSE_PVCCIN_CPU1_PH2_IMON
  AIREF3  = VR_PVCCIN_CPU1_AIREF3
  AISEN3  = ISENSE_PVCCIN_CPU1_PH3_IMON
  AIREF4  = VR_PVCCIN_CPU1_AIREF4
  AISEN4  = ISENSE_PVCCIN_CPU1_PH4_IMON
  AIREF5  = VR_PVCCIN_CPU1_AIREF5
  AISEN5  = ISENSE_PVCCIN_CPU1_PH5_IMON
  AIREF6  = NC
  AISEN6  = NC
  BVSEN  = VSENSE_PVSA_CPU1_BVSP
  BVREF  = VSENSE_PVSA_CPU1_N
  BIREF1  = VR_PVSA_CPU1_BIREF1
  BISEN1  = ISENSE_PVSA_CPU1_IMON
  MP3  = PU_VR_PVCCIN_CPU1_IMON
  MP4  = NC
  XADDR2  = VR_PVCCIN_CPU1_XADDR2
  BTSEN  = A_TSENSE_PVSA_CPU1
  ATSEN  = A_TSENSE_PVCCIN_CPU1
  XADDR1  = VR_PVCCIN_CPU1_XADDR1
  VINSEN  = VR_PVCCIN_CPU1_AVINSEN
  IINSEN  = NC
  VDD  = VR_PVCCIN_CPU1_VDD
  VD12  = VR_PVCCIN_CPU1_VD12
  THPAD  = GND

(kicad_pcb
	(version 20260206)
	(generator "pcbnew")
	(generator_version "10.0")
	(general
		(thickness 1.6)
		(legacy_teardrops no)
	)
	(paper "A4")
	(title_block
		(title "Wiwynn_Tioga_Pass_MB.brd")
		(comment 1 "Tioga Pass / footprint 241 of 4770 (EU1C2), pads 1-17 of 49")
	)
	(layers
		(0 "F.Cu" signal "TOP")
		(4 "In1.Cu" signal "L2GND")
		(6 "In2.Cu" signal "L3")
		(8 "In3.Cu" signal "L4GND")
		(10 "In4.Cu" signal "L5")
		(12 "In5.Cu" signal "L6GND")
		(14 "In6.Cu" signal "L7VCC")
		(16 "In7.Cu" signal "L8VCC")
		(18 "In8.Cu" signal "L9GND")
		(20 "In9.Cu" signal "L10")
		(22 "In10.Cu" signal "L11GND")
		(24 "In11.Cu" signal "L12")
		(26 "In12.Cu" signal "L13GND")
		(2 "B.Cu" signal "BOTTOM")
		(9 "F.Adhes" user "F.Adhesive")
		(11 "B.Adhes" user "B.Adhesive")
		(13 "F.Paste" user "Package Geometry/Pastemask Top")
		(15 "B.Paste" user "Package Geometry/Pastemask Bottom")
		(5 "F.SilkS" user "Ref Des/Silkscreen Top")
		(7 "B.SilkS" user "Ref Des/Silkscreen Bottom")
		(1 "F.Mask" user "Board Geometry/Soldermask Top")
		(3 "B.Mask" user "Board Geometry/Soldermask Bottom")
		(17 "Dwgs.User" user "User.Drawings")
		(19 "Cmts.User" user "User.Comments")
		(21 "Eco1.User" user "User.Eco1")
		(23 "Eco2.User" user "User.Eco2")
		(25 "Edge.Cuts" user "Board Geometry/Outline")
		(27 "Margin" user)
		(31 "F.CrtYd" user "Package Geometry/Place Bound Top")
		(29 "B.CrtYd" user "Package Geometry/Place Bound Bottom")
		(35 "F.Fab" user "Ref Des/Assembly Top")
		(33 "B.Fab" user "Ref Des/Assembly Bottom")
	)
	(footprint ""
		(layer "F.Cu")
		(at 19.431 -92.456)
		(property "Reference" "EU1C2"
			(at -7.8232 -3.45313 0)
			(unlocked yes)
			(layer "F.SilkS")
			(effects
				(font
					(size 0.7874 0.5842)
					(thickness 0.1524)
				)
				(justify left)
			)
		)
		(property "Value" ""
			(at 0 0 0)
			(layer "F.Fab")
			(effects
				(font
					(size 1.27 1.27)
				)
			)
		)
		(duplicate_pad_numbers_are_jumpers no)
		(pad "1" smd custom
			(at -2.8956 -2.199894)
			(size 0.0508 0.0508)
			(layers "F.Cu" "F.Mask" "F.Paste")
			(net "VR_PVSA_CPU1_PWM")
			(options
				(clearance outline)
				(anchor circle)
			)
			(primitives
				(gr_poly
					(pts
						(arc
							(start 0.254 -0.1016)
							(mid 0.3556 0)
							(end 0.254 0.1016)
						)
						(xy -0.3556 0.1016) (xy -0.3556 -0.1016)
					)
					(width 0)
					(fill yes)
				)
			)
		)
		(pad "2" smd custom
			(at -2.8956 -1.800098)
			(size 0.0508 0.0508)
			(layers "F.Cu" "F.Mask" "F.Paste")
			(net "Net_277")
			(options
				(clearance outline)
				(anchor circle)
			)
			(primitives
				(gr_poly
					(pts
						(arc
							(start 0.254 -0.1016)
							(mid 0.3556 0)
							(end 0.254 0.1016)
						)
						(xy -0.3556 0.1016) (xy -0.3556 -0.1016)
					)
					(width 0)
					(fill yes)
				)
			)
		)
		(pad "3" smd custom
			(at -2.8956 -1.400048)
			(size 0.0508 0.0508)
			(layers "F.Cu" "F.Mask" "F.Paste")
			(net "VR_PVCCIN_CPU1_PWM5")
			(options
				(clearance outline)
				(anchor circle)
			)
			(primitives
				(gr_poly
					(pts
						(arc
							(start 0.254 -0.1016)
							(mid 0.3556 0)
							(end 0.254 0.1016)
						)
						(xy -0.3556 0.1016) (xy -0.3556 -0.1016)
					)
					(width 0)
					(fill yes)
				)
			)
		)
		(pad "4" smd custom
			(at -2.8956 -0.999998)
			(size 0.0508 0.0508)
			(layers "F.Cu" "F.Mask" "F.Paste")
			(net "VR_PVCCIN_CPU1_PWM4")
			(options
				(clearance outline)
				(anchor circle)
			)
			(primitives
				(gr_poly
					(pts
						(arc
							(start 0.254 -0.1016)
							(mid 0.3556 0)
							(end 0.254 0.1016)
						)
						(xy -0.3556 0.1016) (xy -0.3556 -0.1016)
					)
					(width 0)
					(fill yes)
				)
			)
		)
		(pad "5" smd custom
			(at -2.8956 -0.599948)
			(size 0.0508 0.0508)
			(layers "F.Cu" "F.Mask" "F.Paste")
			(net "VR_PVCCIN_CPU1_PWM3")
			(options
				(clearance outline)
				(anchor circle)
			)
			(primitives
				(gr_poly
					(pts
						(arc
							(start 0.254 -0.1016)
							(mid 0.3556 0)
							(end 0.254 0.1016)
						)
						(xy -0.3556 0.1016) (xy -0.3556 -0.1016)
					)
					(width 0)
					(fill yes)
				)
			)
		)
		(pad "6" smd custom
			(at -2.8956 -0.199898)
			(size 0.0508 0.0508)
			(layers "F.Cu" "F.Mask" "F.Paste")
			(net "VR_PVCCIN_CPU1_PWM2")
			(options
				(clearance outline)
				(anchor circle)
			)
			(primitives
				(gr_poly
					(pts
						(arc
							(start 0.254 -0.1016)
							(mid 0.3556 0)
							(end 0.254 0.1016)
						)
						(xy -0.3556 0.1016) (xy -0.3556 -0.1016)
					)
					(width 0)
					(fill yes)
				)
			)
		)
		(pad "7" smd custom
			(at -2.8956 0.199898)
			(size 0.0508 0.0508)
			(layers "F.Cu" "F.Mask" "F.Paste")
			(net "VR_PVCCIN_CPU1_PWM1")
			(options
				(clearance outline)
				(anchor circle)
			)
			(primitives
				(gr_poly
					(pts
						(arc
							(start 0.254 -0.1016)
							(mid 0.3556 0)
							(end 0.254 0.1016)
						)
						(xy -0.3556 0.1016) (xy -0.3556 -0.1016)
					)
					(width 0)
					(fill yes)
				)
			)
		)
		(pad "8" smd custom
			(at -2.8956 0.599948)
			(size 0.0508 0.0508)
			(layers "F.Cu" "F.Mask" "F.Paste")
			(net "SMB_VR_STBY_LVC3_SDA")
			(options
				(clearance outline)
				(anchor circle)
			)
			(primitives
				(gr_poly
					(pts
						(arc
							(start 0.254 -0.1016)
							(mid 0.3556 0)
							(end 0.254 0.1016)
						)
						(xy -0.3556 0.1016) (xy -0.3556 -0.1016)
					)
					(width 0)
					(fill yes)
				)
			)
		)
		(pad "9" smd custom
			(at -2.8956 0.999998)
			(size 0.0508 0.0508)
			(layers "F.Cu" "F.Mask" "F.Paste")
			(net "SMB_VR_STBY_LVC3_SCL")
			(options
				(clearance outline)
				(anchor circle)
			)
			(primitives
				(gr_poly
					(pts
						(arc
							(start 0.254 -0.1016)
							(mid 0.3556 0)
							(end 0.254 0.1016)
						)
						(xy -0.3556 0.1016) (xy -0.3556 -0.1016)
					)
					(width 0)
					(fill yes)
				)
			)
		)
		(pad "10" smd custom
			(at -2.8956 1.400048)
			(size 0.0508 0.0508)
			(layers "F.Cu" "F.Mask" "F.Paste")
			(net "Net_278")
			(options
				(clearance outline)
				(anchor circle)
			)
			(primitives
				(gr_poly
					(pts
						(arc
							(start 0.254 -0.1016)
							(mid 0.3556 0)
							(end 0.254 0.1016)
						)
						(xy -0.3556 0.1016) (xy -0.3556 -0.1016)
					)
					(width 0)
					(fill yes)
				)
			)
		)
		(pad "11" smd custom
			(at -2.8956 1.800098)
			(size 0.0508 0.0508)
			(layers "F.Cu" "F.Mask" "F.Paste")
			(net "VR_VRRDY_PVCCIN_CPU1")
			(options
				(clearance outline)
				(anchor circle)
			)
			(primitives
				(gr_poly
					(pts
						(arc
							(start 0.254 -0.1016)
							(mid 0.3556 0)
							(end 0.254 0.1016)
						)
						(xy -0.3556 0.1016) (xy -0.3556 -0.1016)
					)
					(width 0)
					(fill yes)
				)
			)
		)
		(pad "12" smd custom
			(at -2.8956 2.199894)
			(size 0.0508 0.0508)
			(layers "F.Cu" "F.Mask" "F.Paste")
			(net "VR_PVCCIN_CPU1_VREN")
			(options
				(clearance outline)
				(anchor circle)
			)
			(primitives
				(gr_poly
					(pts
						(arc
							(start 0.254 -0.1016)
							(mid 0.3556 0)
							(end 0.254 0.1016)
						)
						(xy -0.3556 0.1016) (xy -0.3556 -0.1016)
					)
					(width 0)
					(fill yes)
				)
			)
		)
		(pad "13" smd custom
			(at -2.199894 2.8956)
			(size 0.0508 0.0508)
			(layers "F.Cu" "F.Mask" "F.Paste")
			(net "IRQ_PVCCIN_CPU1_VRHOT_LVC3_R_N")
			(options
				(clearance outline)
				(anchor circle)
			)
			(primitives
				(gr_poly
					(pts
						(arc
							(start -0.1016 -0.254)
							(mid 0 -0.3556)
							(end 0.1016 -0.254)
						)
						(xy 0.1016 0.3556) (xy -0.1016 0.3556)
					)
					(width 0)
					(fill yes)
				)
			)
		)
		(pad "14" smd custom
			(at -1.800098 2.8956)
			(size 0.0508 0.0508)
			(layers "F.Cu" "F.Mask" "F.Paste")
			(net "FM_PVCCIN_CPU1_PWR_IN_ALERT_N")
			(options
				(clearance outline)
				(anchor circle)
			)
			(primitives
				(gr_poly
					(pts
						(arc
							(start -0.1016 -0.254)
							(mid 0 -0.3556)
							(end 0.1016 -0.254)
						)
						(xy 0.1016 0.3556) (xy -0.1016 0.3556)
					)
					(width 0)
					(fill yes)
				)
			)
		)
		(pad "15" smd custom
			(at -1.400048 2.8956)
			(size 0.0508 0.0508)
			(layers "F.Cu" "F.Mask" "F.Paste")
			(net "PWRGD_PVSA_CPU1_R")
			(options
				(clearance outline)
				(anchor circle)
			)
			(primitives
				(gr_poly
					(pts
						(arc
							(start -0.1016 -0.254)
							(mid 0 -0.3556)
							(end 0.1016 -0.254)
						)
						(xy 0.1016 0.3556) (xy -0.1016 0.3556)
					)
					(width 0)
					(fill yes)
				)
			)
		)
		(pad "16" smd custom
			(at -0.999998 2.8956)
			(size 0.0508 0.0508)
			(layers "F.Cu" "F.Mask" "F.Paste")
			(net "Net_220")
			(options
				(clearance outline)
				(anchor circle)
			)
			(primitives
				(gr_poly
					(pts
						(arc
							(start -0.1016 -0.254)
							(mid 0 -0.3556)
							(end 0.1016 -0.254)
						)
						(xy 0.1016 0.3556) (xy -0.1016 0.3556)
					)
					(width 0)
					(fill yes)
				)
			)
		)
		(pad "17" smd custom
			(at -0.599948 2.8956)
			(size 0.0508 0.0508)
			(layers "F.Cu" "F.Mask" "F.Paste")
			(net "SVID_VCLK_PVCCIN_CPU1")
			(options
				(clearance outline)
				(anchor circle)
			)
			(primitives
				(gr_poly
					(pts
						(arc
							(start -0.1016 -0.254)
							(mid 0 -0.3556)
							(end 0.1016 -0.254)
						)
						(xy 0.1016 0.3556) (xy -0.1016 0.3556)
					)
					(width 0)
					(fill yes)
				)
			)
		)
	)
)
